FILE_TYPE = MULTI_PHYS_TABLE;

PART 'IR3889MTRPBF'

{========================================================================================}
:VALUE          | PART_TYPE | MATERIAL | PART_NUMBER    = STANDARD        | LIFECYCLE     | PART_NUMBER   | JEDEC_TYPE  | DESCRIPTION                       | MANUFTR | MANUF_PN       | RD_CMPLS_LVL | CMPLS_LVL | FROM_PJ    | CLASS | DIP_SMD | DATA                   | EE_CHECK_LIST | FP_ECN             | PSL | CREATOR | STATUS | MSD  | ESD_CDM | ESD_HBM | ESD_MM | PIN_LENGTH_SHORT_PIN | PIN_LENGTH_LONG_PIN | CREATEDAY  ;
{========================================================================================}
 'IR3889MTRPBF' | 'SMLF'    | 'IC'     | 'AL003889000'(!) = ''               | ''               | 'AL003889000' |'QFN22_6X5'| 'IC OTHER(37P) IR3889MTRPBF(QFN)' | 'SNI'   | 'IR3889MTRPBF' | 'EP(V1)'     | ''        | 'S6X-KIMI' | 'IC'  | ''      | 'SNI_IR3889MTRPBF.pdf' | ''            | 'IR3889MTRPBF.msg' | ''  | ''      | ''     | 'NA' | 'NA'    | 'NA'    | 'NA'   | '0 MILS'             | '0 MILS'            | '20200519'
 'IR3889MTRPBF' | 'SMLF'    | 'EMPTY'  | 'AL003889000'(!) = ''               | ''               | 'AL003889000' |'QFN22_6X5'| 'IC OTHER(37P) IR3889MTRPBF(QFN)' | 'SNI'   | 'IR3889MTRPBF' | 'EP(V1)'     | ''        | 'S6X-KIMI' | 'IC'  | ''      | 'SNI_IR3889MTRPBF.pdf' | ''            | 'IR3889MTRPBF.msg' | ''  | ''      | ''     | 'NA' | 'NA'    | 'NA'    | 'NA'   | '0 MILS'             | '0 MILS'            | '20200519'

END_PART

END.

